(kicad_pcb
	(version 20260206)
	(generator "pcbnew")
	(generator_version "10.0")
	(general
		(thickness 1.6)
		(legacy_teardrops no)
	)
	(paper "A4")
	(title_block
		(title "Bryce Canyon_IOM_IOC_16318-2_OCP.brd")
		(comment 1 "Bryce Canyon / footprints 1171-1178 of 1605")
	)
	(layers
		(0 "F.Cu" signal "TOP")
		(4 "In1.Cu" signal "L2GND")
		(6 "In2.Cu" signal "L3")
		(8 "In3.Cu" signal "L4VCC")
		(10 "In4.Cu" signal "L5VCC")
		(12 "In5.Cu" signal "L6")
		(14 "In6.Cu" signal "L7GND")
		(2 "B.Cu" signal "BOTTOM")
		(9 "F.Adhes" user "F.Adhesive")
		(11 "B.Adhes" user "B.Adhesive")
		(13 "F.Paste" user "Package Geometry/Pastemask Top")
		(15 "B.Paste" user "Package Geometry/Pastemask Bottom")
		(5 "F.SilkS" user "Ref Des/Silkscreen Top")
		(7 "B.SilkS" user "Ref Des/Silkscreen Bottom")
		(1 "F.Mask" user "Board Geometry/Soldermask Top")
		(3 "B.Mask" user "Board Geometry/Soldermask Bottom")
		(17 "Dwgs.User" user "User.Drawings")
		(19 "Cmts.User" user "User.Comments")
		(21 "Eco1.User" user "User.Eco1")
		(23 "Eco2.User" user "User.Eco2")
		(25 "Edge.Cuts" user "Board Geometry/Outline")
		(27 "Margin" user)
		(31 "F.CrtYd" user "Package Geometry/Place Bound Top")
		(29 "B.CrtYd" user "Package Geometry/Place Bound Bottom")
		(35 "F.Fab" user "Ref Des/Assembly Top")
		(33 "B.Fab" user "Ref Des/Assembly Bottom")
	)
	(footprint ""
		(layer "B.Cu")
		(at 38.42131 -122.188478 -90)
		(property "Reference" "R337"
			(at 0 0 90)
			(layer "B.SilkS")
			(hide yes)
			(effects
				(font
					(size 1.27 1.27)
				)
				(justify mirror)
			)
		)
		(property "Value" "4K7R2F-GP"
			(at -0.064008 -3.993896 270)
			(unlocked yes)
			(layer "B.Fab")
			(hide yes)
			(effects
				(font
					(size 1.016 1.016)
					(thickness 0.1524)
				)
				(justify mirror)
			)
		)
		(property "Device Type" "R402H16"
			(at -0.064008 -5.517896 270)
			(unlocked yes)
			(layer "B.Fab")
			(hide yes)
			(effects
				(font
					(size 1.016 1.016)
					(thickness 0.1524)
				)
				(justify mirror)
			)
		)
		(duplicate_pad_numbers_are_jumpers no)
		(fp_line
			(start -0.508 -0.9398)
			(end 0.508 -0.9398)
			(stroke
				(width 0.1524)
				(type default)
			)
			(layer "B.SilkS")
		)
		(fp_line
			(start 0.508 -0.9398)
			(end 0.508 0.9398)
			(stroke
				(width 0.1524)
				(type default)
			)
			(layer "B.SilkS")
		)
		(fp_rect
			(start 0.508 0.9398)
			(end -0.508 -0.9398)
			(stroke
				(width 0)
				(type default)
			)
			(fill no)
			(layer "B.CrtYd")
		)
		(fp_rect
			(start 0.508 0.9398)
			(end -0.508 -0.9398)
			(stroke
				(width 0)
				(type default)
			)
			(fill no)
			(layer "B.Fab")
		)
		(pad "1" smd custom
			(at 0 -0.4445 90)
			(size 0.1397 0.1397)
			(layers "B.Cu" "B.Mask" "B.Paste")
			(net "TEMP_3_A0")
			(options
				(clearance outline)
				(anchor circle)
			)
			(primitives
				(gr_poly
					(pts
						(arc
							(start -0.1778 0.2794)
							(mid -0.249642 0.249642)
							(end -0.2794 0.1778)
						)
						(arc
							(start -0.2794 -0.1778)
							(mid -0.249642 -0.249642)
							(end -0.1778 -0.2794)
						)
						(arc
							(start 0.1778 -0.2794)
							(mid 0.249642 -0.249642)
							(end 0.2794 -0.1778)
						)
						(arc
							(start 0.2794 0.1778)
							(mid 0.249642 0.249642)
							(end 0.1778 0.2794)
						)
					)
					(width 0)
					(fill yes)
				)
			)
		)
		(pad "2" smd custom
			(at 0 0.4445 90)
			(size 0.1397 0.1397)
			(layers "B.Cu" "B.Mask" "B.Paste")
			(net "GND")
			(options
				(clearance outline)
				(anchor circle)
			)
			(primitives
				(gr_poly
					(pts
						(arc
							(start -0.1778 0.2794)
							(mid -0.249642 0.249642)
							(end -0.2794 0.1778)
						)
						(arc
							(start -0.2794 -0.1778)
							(mid -0.249642 -0.249642)
							(end -0.1778 -0.2794)
						)
						(arc
							(start 0.1778 -0.2794)
							(mid 0.249642 -0.249642)
							(end 0.2794 -0.1778)
						)
						(arc
							(start 0.2794 0.1778)
							(mid 0.249642 0.249642)
							(end 0.1778 0.2794)
						)
					)
					(width 0)
					(fill yes)
				)
			)
		)
	)
	(footprint ""
		(layer "B.Cu")
		(at 95.25 -6.223 90)
		(property "Reference" "C525"
			(at 0 0 90)
			(layer "B.SilkS")
			(hide yes)
			(effects
				(font
					(size 1.27 1.27)
				)
				(justify mirror)
			)
		)
		(property "Value" "SC1000P2KV6KX-GP-U"
			(at -0.0508 -3.5052 90)
			(unlocked yes)
			(layer "B.Fab")
			(hide yes)
			(effects
				(font
					(size 1.016 1.016)
					(thickness 0.1524)
				)
				(justify mirror)
			)
		)
		(property "Device Type" "C1206H58"
			(at -0.0508 -5.0292 90)
			(unlocked yes)
			(layer "B.Fab")
			(hide yes)
			(effects
				(font
					(size 1.016 1.016)
					(thickness 0.1524)
				)
				(justify mirror)
			)
		)
		(duplicate_pad_numbers_are_jumpers no)
		(fp_line
			(start 1.016 -2.2352)
			(end 1.016 -0.8382)
			(stroke
				(width 0.1524)
				(type default)
			)
			(layer "B.SilkS")
		)
		(fp_line
			(start -1.016 -2.2352)
			(end 1.016 -2.2352)
			(stroke
				(width 0.1524)
				(type default)
			)
			(layer "B.SilkS")
		)
		(fp_line
			(start -1.016 -2.2352)
			(end -1.016 -0.8382)
			(stroke
				(width 0.1524)
				(type default)
			)
			(layer "B.SilkS")
		)
		(fp_line
			(start -1.016 0.8382)
			(end -1.016 2.2352)
			(stroke
				(width 0.1524)
				(type default)
			)
			(layer "B.SilkS")
		)
		(fp_line
			(start 1.016 2.2352)
			(end 1.016 0.8128)
			(stroke
				(width 0.1524)
				(type default)
			)
			(layer "B.SilkS")
		)
		(fp_line
			(start -1.016 2.2352)
			(end 1.016 2.2352)
			(stroke
				(width 0.1524)
				(type default)
			)
			(layer "B.SilkS")
		)
		(fp_rect
			(start 1.0922 2.3114)
			(end -1.0922 -2.3114)
			(stroke
				(width 0)
				(type default)
			)
			(fill no)
			(layer "B.CrtYd")
		)
		(fp_poly
			(pts
				(xy 1.0922 -2.3114) (xy -1.0922 -2.3114) (xy -1.0922 2.3114) (xy 1.0922 2.3114)
			)
			(stroke
				(width 0)
				(type default)
			)
			(fill no)
			(layer "B.Fab")
		)
		(pad "1" smd rect
			(at 0 -1.397 270)
			(size 1.651 1.27)
			(layers "B.Cu" "B.Mask" "B.Paste")
			(net "USB_CONN_GND")
		)
		(pad "2" smd rect
			(at 0 1.397 270)
			(size 1.651 1.27)
			(layers "B.Cu" "B.Mask" "B.Paste")
			(net "GND")
		)
	)
	(footprint ""
		(layer "B.Cu")
		(at 63.00851 -150.9395 -90)
		(property "Reference" "R393"
			(at 0 0 90)
			(layer "B.SilkS")
			(hide yes)
			(effects
				(font
					(size 1.27 1.27)
				)
				(justify mirror)
			)
		)
		(property "Value" "4K7R2F-GP"
			(at -0.064008 -3.993896 270)
			(unlocked yes)
			(layer "B.Fab")
			(hide yes)
			(effects
				(font
					(size 1.016 1.016)
					(thickness 0.1524)
				)
				(justify mirror)
			)
		)
		(property "Device Type" "R402H16"
			(at -0.064008 -5.517896 270)
			(unlocked yes)
			(layer "B.Fab")
			(hide yes)
			(effects
				(font
					(size 1.016 1.016)
					(thickness 0.1524)
				)
				(justify mirror)
			)
		)
		(duplicate_pad_numbers_are_jumpers no)
		(fp_line
			(start -0.508 -0.9398)
			(end 0.508 -0.9398)
			(stroke
				(width 0.1524)
				(type default)
			)
			(layer "B.SilkS")
		)
		(fp_line
			(start 0.508 -0.9398)
			(end 0.508 0.9398)
			(stroke
				(width 0.1524)
				(type default)
			)
			(layer "B.SilkS")
		)
		(fp_rect
			(start 0.508 0.9398)
			(end -0.508 -0.9398)
			(stroke
				(width 0)
				(type default)
			)
			(fill no)
			(layer "B.CrtYd")
		)
		(fp_rect
			(start 0.508 0.9398)
			(end -0.508 -0.9398)
			(stroke
				(width 0)
				(type default)
			)
			(fill no)
			(layer "B.Fab")
		)
		(pad "1" smd custom
			(at 0 -0.4445 90)
			(size 0.1397 0.1397)
			(layers "B.Cu" "B.Mask" "B.Paste")
			(net "P3V3_STBY")
			(options
				(clearance outline)
				(anchor circle)
			)
			(primitives
				(gr_poly
					(pts
						(arc
							(start -0.1778 0.2794)
							(mid -0.249642 0.249642)
							(end -0.2794 0.1778)
						)
						(arc
							(start -0.2794 -0.1778)
							(mid -0.249642 -0.249642)
							(end -0.1778 -0.2794)
						)
						(arc
							(start 0.1778 -0.2794)
							(mid 0.249642 -0.249642)
							(end 0.2794 -0.1778)
						)
						(arc
							(start 0.2794 0.1778)
							(mid 0.249642 0.249642)
							(end 0.1778 0.2794)
						)
					)
					(width 0)
					(fill yes)
				)
			)
		)
		(pad "2" smd custom
			(at 0 0.4445 90)
			(size 0.1397 0.1397)
			(layers "B.Cu" "B.Mask" "B.Paste")
			(net "MAC2_TXD2")
			(options
				(clearance outline)
				(anchor circle)
			)
			(primitives
				(gr_poly
					(pts
						(arc
							(start -0.1778 0.2794)
							(mid -0.249642 0.249642)
							(end -0.2794 0.1778)
						)
						(arc
							(start -0.2794 -0.1778)
							(mid -0.249642 -0.249642)
							(end -0.1778 -0.2794)
						)
						(arc
							(start 0.1778 -0.2794)
							(mid 0.249642 -0.249642)
							(end 0.2794 -0.1778)
						)
						(arc
							(start 0.2794 0.1778)
							(mid 0.249642 0.249642)
							(end 0.1778 0.2794)
						)
					)
					(width 0)
					(fill yes)
				)
			)
		)
	)
	(footprint ""
		(layer "B.Cu")
		(at 50.702464 -157.62986 -90)
		(property "Reference" "R281"
			(at 0 0 90)
			(layer "B.SilkS")
			(hide yes)
			(effects
				(font
					(size 1.27 1.27)
				)
				(justify mirror)
			)
		)
		(property "Value" "0R2J-2-GP"
			(at -0.064008 -3.993896 270)
			(unlocked yes)
			(layer "B.Fab")
			(hide yes)
			(effects
				(font
					(size 1.016 1.016)
					(thickness 0.1524)
				)
				(justify mirror)
			)
		)
		(property "Device Type" "R402H16"
			(at -0.064008 -5.517896 270)
			(unlocked yes)
			(layer "B.Fab")
			(hide yes)
			(effects
				(font
					(size 1.016 1.016)
					(thickness 0.1524)
				)
				(justify mirror)
			)
		)
		(duplicate_pad_numbers_are_jumpers no)
		(fp_line
			(start -0.508 -0.9398)
			(end 0.508 -0.9398)
			(stroke
				(width 0.1524)
				(type default)
			)
			(layer "B.SilkS")
		)
		(fp_line
			(start 0.508 -0.9398)
			(end 0.508 0.9398)
			(stroke
				(width 0.1524)
				(type default)
			)
			(layer "B.SilkS")
		)
		(fp_rect
			(start 0.508 0.9398)
			(end -0.508 -0.9398)
			(stroke
				(width 0)
				(type default)
			)
			(fill no)
			(layer "B.CrtYd")
		)
		(fp_rect
			(start 0.508 0.9398)
			(end -0.508 -0.9398)
			(stroke
				(width 0)
				(type default)
			)
			(fill no)
			(layer "B.Fab")
		)
		(pad "1" smd custom
			(at 0 -0.4445 90)
			(size 0.1397 0.1397)
			(layers "B.Cu" "B.Mask" "B.Paste")
			(net "I2C_MEZZ_OOB_SDA")
			(options
				(clearance outline)
				(anchor circle)
			)
			(primitives
				(gr_poly
					(pts
						(arc
							(start -0.1778 0.2794)
							(mid -0.249642 0.249642)
							(end -0.2794 0.1778)
						)
						(arc
							(start -0.2794 -0.1778)
							(mid -0.249642 -0.249642)
							(end -0.1778 -0.2794)
						)
						(arc
							(start 0.1778 -0.2794)
							(mid 0.249642 -0.249642)
							(end 0.2794 -0.1778)
						)
						(arc
							(start 0.2794 0.1778)
							(mid 0.249642 0.249642)
							(end 0.1778 0.2794)
						)
					)
					(width 0)
					(fill yes)
				)
			)
		)
		(pad "2" smd custom
			(at 0 0.4445 90)
			(size 0.1397 0.1397)
			(layers "B.Cu" "B.Mask" "B.Paste")
			(net "BMC_SMB5_DAT")
			(options
				(clearance outline)
				(anchor circle)
			)
			(primitives
				(gr_poly
					(pts
						(arc
							(start -0.1778 0.2794)
							(mid -0.249642 0.249642)
							(end -0.2794 0.1778)
						)
						(arc
							(start -0.2794 -0.1778)
							(mid -0.249642 -0.249642)
							(end -0.1778 -0.2794)
						)
						(arc
							(start 0.1778 -0.2794)
							(mid 0.249642 -0.249642)
							(end 0.2794 -0.1778)
						)
						(arc
							(start 0.2794 0.1778)
							(mid 0.249642 0.249642)
							(end 0.1778 0.2794)
						)
					)
					(width 0)
					(fill yes)
				)
			)
		)
	)
	(footprint ""
		(layer "B.Cu")
		(at 178.695604 -70.088506)
		(property "Reference" "TP125"
			(at 0 0 0)
			(layer "B.SilkS")
			(hide yes)
			(effects
				(font
					(size 1.27 1.27)
				)
				(justify mirror)
			)
		)
		(property "Value" "TPAD28-2-GP"
			(at 0.0127 -1.6637 0)
			(unlocked yes)
			(layer "B.Fab")
			(hide yes)
			(effects
				(font
					(size 1.016 1.016)
					(thickness 0.1524)
				)
				(justify mirror)
			)
		)
		(property "Device Type" "TPAD28"
			(at 0.0127 -3.1877 0)
			(unlocked yes)
			(layer "B.Fab")
			(hide yes)
			(effects
				(font
					(size 1.016 1.016)
					(thickness 0.1524)
				)
				(justify mirror)
			)
		)
		(duplicate_pad_numbers_are_jumpers no)
		(fp_poly
			(pts
				(arc
					(start 0.3556 0)
					(mid -0.3556 0)
					(end 0.3556 0)
				)
			)
			(stroke
				(width 0)
				(type default)
			)
			(fill no)
			(layer "B.CrtYd")
		)
		(fp_poly
			(pts
				(arc
					(start 0.6096 0)
					(mid -0.6096 0)
					(end 0.6096 0)
				)
			)
			(stroke
				(width 0)
				(type default)
			)
			(fill no)
			(layer "B.Fab")
		)
		(pad "1" smd circle
			(at 0 0 180)
			(size 0.7112 0.7112)
			(layers "B.Cu" "B.Mask" "B.Paste")
			(net "IOC_GPIO_33")
		)
	)
	(footprint ""
		(layer "B.Cu")
		(at 190.8175 -64.8208 90)
		(property "Reference" "C396"
			(at 0 0 90)
			(layer "B.SilkS")
			(hide yes)
			(effects
				(font
					(size 1.27 1.27)
				)
				(justify mirror)
			)
		)
		(property "Value" "SCD1U6D3V1KX-GP"
			(at 2.8321 -1.7399 90)
			(unlocked yes)
			(layer "B.Fab")
			(hide yes)
			(effects
				(font
					(size 1.016 1.016)
					(thickness 0.1524)
				)
				(justify mirror)
			)
		)
		(property "Device Type" "C0201H13"
			(at 2.8321 -3.2639 90)
			(unlocked yes)
			(layer "B.Fab")
			(hide yes)
			(effects
				(font
					(size 1.016 1.016)
					(thickness 0.1524)
				)
				(justify mirror)
			)
		)
		(duplicate_pad_numbers_are_jumpers no)
		(fp_rect
			(start 0.2794 0.6477)
			(end -0.2794 -0.6477)
			(stroke
				(width 0)
				(type default)
			)
			(fill no)
			(layer "B.CrtYd")
		)
		(fp_rect
			(start 0.2794 0.6477)
			(end -0.2794 -0.6477)
			(stroke
				(width 0)
				(type default)
			)
			(fill no)
			(layer "B.Fab")
		)
		(pad "1" smd custom
			(at 0 -0.2794 270)
			(size 0.0762 0.0762)
			(layers "B.Cu" "B.Mask" "B.Paste")
			(net "P0V975")
			(options
				(clearance outline)
				(anchor circle)
			)
			(primitives
				(gr_poly
					(pts
						(arc
							(start 0.1524 0.127)
							(mid 0.137521 0.162921)
							(end 0.1016 0.1778)
						)
						(arc
							(start -0.1016 0.1778)
							(mid -0.137521 0.162921)
							(end -0.1524 0.127)
						)
						(arc
							(start -0.1524 -0.127)
							(mid -0.137521 -0.162921)
							(end -0.1016 -0.1778)
						)
						(arc
							(start 0.1016 -0.1778)
							(mid 0.137521 -0.162921)
							(end 0.1524 -0.127)
						)
					)
					(width 0)
					(fill yes)
				)
			)
		)
		(pad "2" smd custom
			(at 0 0.2794 270)
			(size 0.0762 0.0762)
			(layers "B.Cu" "B.Mask" "B.Paste")
			(net "GND")
			(options
				(clearance outline)
				(anchor circle)
			)
			(primitives
				(gr_poly
					(pts
						(arc
							(start 0.1524 0.127)
							(mid 0.137521 0.162921)
							(end 0.1016 0.1778)
						)
						(arc
							(start -0.1016 0.1778)
							(mid -0.137521 0.162921)
							(end -0.1524 0.127)
						)
						(arc
							(start -0.1524 -0.127)
							(mid -0.137521 -0.162921)
							(end -0.1016 -0.1778)
						)
						(arc
							(start 0.1016 -0.1778)
							(mid 0.137521 -0.162921)
							(end 0.1524 -0.127)
						)
					)
					(width 0)
					(fill yes)
				)
			)
		)
	)
	(footprint ""
		(layer "B.Cu")
		(at 32.37738 -126.8349 90)
		(property "Reference" "R734"
			(at 0 0 90)
			(layer "B.SilkS")
			(hide yes)
			(effects
				(font
					(size 1.27 1.27)
				)
				(justify mirror)
			)
		)
		(property "Value" "0R2J-2-GP"
			(at -0.064008 -3.993896 90)
			(unlocked yes)
			(layer "B.Fab")
			(hide yes)
			(effects
				(font
					(size 1.016 1.016)
					(thickness 0.1524)
				)
				(justify mirror)
			)
		)
		(property "Device Type" "R402H16"
			(at -0.064008 -5.517896 90)
			(unlocked yes)
			(layer "B.Fab")
			(hide yes)
			(effects
				(font
					(size 1.016 1.016)
					(thickness 0.1524)
				)
				(justify mirror)
			)
		)
		(duplicate_pad_numbers_are_jumpers no)
		(fp_line
			(start 0.508 -0.9398)
			(end 0.508 0.9398)
			(stroke
				(width 0.1524)
				(type default)
			)
			(layer "B.SilkS")
		)
		(fp_line
			(start -0.508 -0.9398)
			(end 0.508 -0.9398)
			(stroke
				(width 0.1524)
				(type default)
			)
			(layer "B.SilkS")
		)
		(fp_rect
			(start 0.508 0.9398)
			(end -0.508 -0.9398)
			(stroke
				(width 0)
				(type default)
			)
			(fill no)
			(layer "B.CrtYd")
		)
		(fp_rect
			(start 0.508 0.9398)
			(end -0.508 -0.9398)
			(stroke
				(width 0)
				(type default)
			)
			(fill no)
			(layer "B.Fab")
		)
		(pad "1" smd custom
			(at 0 -0.4445 270)
			(size 0.1397 0.1397)
			(layers "B.Cu" "B.Mask" "B.Paste")
			(net "U104_EN")
			(options
				(clearance outline)
				(anchor circle)
			)
			(primitives
				(gr_poly
					(pts
						(arc
							(start -0.1778 0.2794)
							(mid -0.249642 0.249642)
							(end -0.2794 0.1778)
						)
						(arc
							(start -0.2794 -0.1778)
							(mid -0.249642 -0.249642)
							(end -0.1778 -0.2794)
						)
						(arc
							(start 0.1778 -0.2794)
							(mid 0.249642 -0.249642)
							(end 0.2794 -0.1778)
						)
						(arc
							(start 0.2794 0.1778)
							(mid 0.249642 0.249642)
							(end 0.1778 0.2794)
						)
					)
					(width 0)
					(fill yes)
				)
			)
		)
		(pad "2" smd custom
			(at 0 0.4445 270)
			(size 0.1397 0.1397)
			(layers "B.Cu" "B.Mask" "B.Paste")
			(net "SYS_RST_EN")
			(options
				(clearance outline)
				(anchor circle)
			)
			(primitives
				(gr_poly
					(pts
						(arc
							(start -0.1778 0.2794)
							(mid -0.249642 0.249642)
							(end -0.2794 0.1778)
						)
						(arc
							(start -0.2794 -0.1778)
							(mid -0.249642 -0.249642)
							(end -0.1778 -0.2794)
						)
						(arc
							(start 0.1778 -0.2794)
							(mid 0.249642 -0.249642)
							(end 0.2794 -0.1778)
						)
						(arc
							(start 0.2794 0.1778)
							(mid 0.249642 0.249642)
							(end 0.1778 0.2794)
						)
					)
					(width 0)
					(fill yes)
				)
			)
		)
	)
	(footprint ""
		(layer "B.Cu")
		(at 45.300392 -144.335754 90)
		(property "Reference" "C56"
			(at 0 0 90)
			(layer "B.SilkS")
			(hide yes)
			(effects
				(font
					(size 1.27 1.27)
				)
				(justify mirror)
			)
		)
		(property "Value" "SC1U16V3KX-5GP"
			(at 0 -2.8194 90)
			(unlocked yes)
			(layer "B.Fab")
			(hide yes)
			(effects
				(font
					(size 1.016 1.016)
					(thickness 0.1524)
				)
				(justify mirror)
			)
		)
		(property "Device Type" "C603H36"
			(at 0 -4.3434 90)
			(unlocked yes)
			(layer "B.Fab")
			(hide yes)
			(effects
				(font
					(size 1.016 1.016)
					(thickness 0.1524)
				)
				(justify mirror)
			)
		)
		(duplicate_pad_numbers_are_jumpers no)
		(fp_line
			(start -0.508 0)
			(end 0.508 0)
			(stroke
				(width 0.2032)
				(type default)
			)
			(layer "B.SilkS")
		)
		(fp_rect
			(start 0.5842 1.3335)
			(end -0.5842 -1.3335)
			(stroke
				(width 0)
				(type default)
			)
			(fill no)
			(layer "B.CrtYd")
		)
		(fp_rect
			(start 0.5842 1.3335)
			(end -0.5842 -1.3335)
			(stroke
				(width 0)
				(type default)
			)
			(fill no)
			(layer "B.Fab")
		)
		(pad "1" smd custom
			(at 0 -0.762 270)
			(size 0.2159 0.2159)
			(layers "B.Cu" "B.Mask" "B.Paste")
			(net "P1V2_STBY")
			(options
				(clearance outline)
				(anchor circle)
			)
			(primitives
				(gr_poly
					(pts
						(arc
							(start -0.3302 0.4318)
							(mid -0.402042 0.402042)
							(end -0.4318 0.3302)
						)
						(arc
							(start -0.4318 -0.3302)
							(mid -0.402042 -0.402042)
							(end -0.3302 -0.4318)
						)
						(arc
							(start 0.3302 -0.4318)
							(mid 0.402042 -0.402042)
							(end 0.4318 -0.3302)
						)
						(arc
							(start 0.4318 0.3302)
							(mid 0.402042 0.402042)
							(end 0.3302 0.4318)
						)
					)
					(width 0)
					(fill yes)
				)
			)
		)
		(pad "2" smd custom
			(at 0 0.762 270)
			(size 0.2159 0.2159)
			(layers "B.Cu" "B.Mask" "B.Paste")
			(net "GND")
			(options
				(clearance outline)
				(anchor circle)
			)
			(primitives
				(gr_poly
					(pts
						(arc
							(start -0.3302 0.4318)
							(mid -0.402042 0.402042)
							(end -0.4318 0.3302)
						)
						(arc
							(start -0.4318 -0.3302)
							(mid -0.402042 -0.402042)
							(end -0.3302 -0.4318)
						)
						(arc
							(start 0.3302 -0.4318)
							(mid 0.402042 -0.402042)
							(end 0.4318 -0.3302)
						)
						(arc
							(start 0.4318 0.3302)
							(mid 0.402042 0.402042)
							(end 0.3302 0.4318)
						)
					)
					(width 0)
					(fill yes)
				)
			)
		)
	)
)
